# BASEBOARD_FAB2 (Tioga Pass) — schematic netlist excerpt (pin names and nets, part order shuffled) for the footprints in the layout excerpt that follows; sources: Cadence DE-HDL packaged netlist, KiCad conversion of Wiwynn_Tioga_Pass_MB.brd

EU9F1  RT9059  IC  pkg DFN  page 238
  VOUT(0)  = P1V15_AUX_BMC
  VOUT(1)  = P1V15_AUX_BMC
  VOUT(2)  = P1V15_AUX_BMC
  ADJ_NC  = VR_P1V15_BMC_STBY_FB
  PGOOD  = PWRGD_P1V15_BMC_STBY_R
  EN  = PWRGD_P1V2_BMC_STBY
  VIN(0)  = P3V3_STBY
  VIN(1)  = P3V3_STBY
  VIN(2)  = P3V3_STBY
  VDD  = P3V3_STBY
  GND  = GND

R1W6  1MR2F-L-GP  1%  pkg SMD-RG1  page 250 : \1\ = P3V3_STBY ; \2\ = FM_OCP_MEZZC_PRES_N

(kicad_pcb
	(version 20260206)
	(generator "pcbnew")
	(generator_version "10.0")
	(general
		(thickness 1.6)
		(legacy_teardrops no)
	)
	(paper "A4")
	(title_block
		(title "Wiwynn_Tioga_Pass_MB.brd")
		(comment 1 "Tioga Pass / footprints 1519-1520 of 4770")
	)
	(layers
		(0 "F.Cu" signal "TOP")
		(4 "In1.Cu" signal "L2GND")
		(6 "In2.Cu" signal "L3")
		(8 "In3.Cu" signal "L4GND")
		(10 "In4.Cu" signal "L5")
		(12 "In5.Cu" signal "L6GND")
		(14 "In6.Cu" signal "L7VCC")
		(16 "In7.Cu" signal "L8VCC")
		(18 "In8.Cu" signal "L9GND")
		(20 "In9.Cu" signal "L10")
		(22 "In10.Cu" signal "L11GND")
		(24 "In11.Cu" signal "L12")
		(26 "In12.Cu" signal "L13GND")
		(2 "B.Cu" signal "BOTTOM")
		(9 "F.Adhes" user "F.Adhesive")
		(11 "B.Adhes" user "B.Adhesive")
		(13 "F.Paste" user "Package Geometry/Pastemask Top")
		(15 "B.Paste" user "Package Geometry/Pastemask Bottom")
		(5 "F.SilkS" user "Ref Des/Silkscreen Top")
		(7 "B.SilkS" user "Ref Des/Silkscreen Bottom")
		(1 "F.Mask" user "Board Geometry/Soldermask Top")
		(3 "B.Mask" user "Board Geometry/Soldermask Bottom")
		(17 "Dwgs.User" user "User.Drawings")
		(19 "Cmts.User" user "User.Comments")
		(21 "Eco1.User" user "User.Eco1")
		(23 "Eco2.User" user "User.Eco2")
		(25 "Edge.Cuts" user "Board Geometry/Outline")
		(27 "Margin" user)
		(31 "F.CrtYd" user "Package Geometry/Place Bound Top")
		(29 "B.CrtYd" user "Package Geometry/Place Bound Bottom")
		(35 "F.Fab" user "Ref Des/Assembly Top")
		(33 "B.Fab" user "Ref Des/Assembly Bottom")
	)
	(footprint ""
		(layer "F.Cu")
		(at 415.1249 -51.5747 180)
		(property "Reference" "R1W6"
			(at 0 0 180)
			(layer "F.SilkS")
			(hide yes)
			(effects
				(font
					(size 1.27 1.27)
				)
			)
		)
		(property "Value" "*"
			(at 0.064008 -4.108196 180)
			(unlocked yes)
			(layer "F.Fab")
			(hide yes)
			(effects
				(font
					(size 1.27 1.016)
					(thickness 0.1524)
				)
			)
		)
		(property "Device Type" "1MR2F-L-GP_SMD-RG1-1MR2F-L-GP,A"
			(at 0.064008 -5.632196 180)
			(unlocked yes)
			(layer "F.Fab")
			(hide yes)
			(effects
				(font
					(size 1.27 1.016)
					(thickness 0.1524)
				)
			)
		)
		(duplicate_pad_numbers_are_jumpers no)
		(fp_line
			(start 0.508 -0.9398)
			(end -0.508 -0.9398)
			(stroke
				(width 0.1524)
				(type default)
			)
			(layer "F.SilkS")
		)
		(fp_line
			(start -0.508 -0.9398)
			(end -0.508 0.9398)
			(stroke
				(width 0.1524)
				(type default)
			)
			(layer "F.SilkS")
		)
		(fp_rect
			(start -0.508 0.9398)
			(end 0.508 -0.9398)
			(stroke
				(width 0)
				(type default)
			)
			(fill no)
			(layer "F.CrtYd")
		)
		(fp_rect
			(start -0.508 0.9398)
			(end 0.508 -0.9398)
			(stroke
				(width 0)
				(type default)
			)
			(fill no)
			(layer "F.Fab")
		)
		(pad "1" smd custom
			(at 0 -0.4445 180)
			(size 0.1397 0.1397)
			(layers "F.Cu" "F.Mask" "F.Paste")
			(net "P3V3_STBY")
			(options
				(clearance outline)
				(anchor circle)
			)
			(primitives
				(gr_poly
					(pts
						(arc
							(start -0.1778 -0.2794)
							(mid -0.249642 -0.249642)
							(end -0.2794 -0.1778)
						)
						(arc
							(start -0.2794 0.1778)
							(mid -0.249642 0.249642)
							(end -0.1778 0.2794)
						)
						(arc
							(start 0.1778 0.2794)
							(mid 0.249642 0.249642)
							(end 0.2794 0.1778)
						)
						(arc
							(start 0.2794 -0.1778)
							(mid 0.249642 -0.249642)
							(end 0.1778 -0.2794)
						)
					)
					(width 0)
					(fill yes)
				)
			)
		)
		(pad "2" smd custom
			(at 0 0.4445 180)
			(size 0.1397 0.1397)
			(layers "F.Cu" "F.Mask" "F.Paste")
			(net "FM_OCP_MEZZC_PRES_N")
			(options
				(clearance outline)
				(anchor circle)
			)
			(primitives
				(gr_poly
					(pts
						(arc
							(start -0.1778 -0.2794)
							(mid -0.249642 -0.249642)
							(end -0.2794 -0.1778)
						)
						(arc
							(start -0.2794 0.1778)
							(mid -0.249642 0.249642)
							(end -0.1778 0.2794)
						)
						(arc
							(start 0.1778 0.2794)
							(mid 0.249642 0.249642)
							(end 0.2794 0.1778)
						)
						(arc
							(start 0.2794 -0.1778)
							(mid 0.249642 -0.249642)
							(end 0.1778 -0.2794)
						)
					)
					(width 0)
					(fill yes)
				)
			)
		)
	)
	(footprint ""
		(layer "F.Cu")
		(at 460.463392 -41.512998)
		(property "Reference" "EU9F1"
			(at -0.256286 -1.396238 0)
			(unlocked yes)
			(layer "F.SilkS")
			(effects
				(font
					(size 0.7874 0.5842)
					(thickness 0.1524)
				)
				(justify left)
			)
		)
		(property "Value" ""
			(at 0 0 0)
			(layer "F.Fab")
			(effects
				(font
					(size 1.27 1.27)
				)
			)
		)
		(duplicate_pad_numbers_are_jumpers no)
		(fp_circle
			(center -0.835152 -0.417322)
			(end -0.708406 -0.417322)
			(stroke
				(width 0.254)
				(type default)
			)
			(fill no)
			(layer "F.SilkS")
		)
		(fp_poly
			(pts
				(xy -0.064516 -1.0922) (xy -0.064516 -0.3302) (xy 0.697484 -1.0922)
			)
			(stroke
				(width 0)
				(type default)
			)
			(fill yes)
			(layer "F.SilkS")
		)
		(fp_rect
			(start 0.597408 2.295398)
			(end 2.273808 -0.295402)
			(stroke
				(width 0)
				(type default)
			)
			(fill yes)
			(layer "F.Paste")
		)
		(fp_rect
			(start -0.064516 2.500122)
			(end 2.935478 -0.500126)
			(stroke
				(width 0)
				(type default)
			)
			(fill no)
			(layer "F.CrtYd")
		)
		(fp_line
			(start -0.064516 -0.500126)
			(end 2.935478 -0.500126)
			(stroke
				(width 0.1)
				(type default)
			)
			(layer "F.Fab")
		)
		(fp_line
			(start -0.064516 2.500122)
			(end -0.064516 -0.500126)
			(stroke
				(width 0.1)
				(type default)
			)
			(layer "F.Fab")
		)
		(fp_line
			(start 2.935478 -0.500126)
			(end 2.935478 2.500122)
			(stroke
				(width 0.1)
				(type default)
			)
			(layer "F.Fab")
		)
		(fp_line
			(start 2.935478 2.500122)
			(end -0.064516 2.500122)
			(stroke
				(width 0.1)
				(type default)
			)
			(layer "F.Fab")
		)
		(fp_circle
			(center -0.835152 -0.417322)
			(end -0.708406 -0.417322)
			(stroke
				(width 0.254)
				(type default)
			)
			(fill no)
			(layer "F.Fab")
		)
		(pad "1" smd rect
			(at 0 0)
			(size 0.6858 0.3048)
			(layers "F.Cu" "F.Mask" "F.Paste")
			(net "P1V15_AUX_BMC")
		)
		(pad "2" smd rect
			(at 0 0.500126)
			(size 0.6858 0.3048)
			(layers "F.Cu" "F.Mask" "F.Paste")
			(net "P1V15_AUX_BMC")
		)
		(pad "3" smd rect
			(at 0 0.999998)
			(size 0.6858 0.3048)
			(layers "F.Cu" "F.Mask" "F.Paste")
			(net "P1V15_AUX_BMC")
		)
		(pad "4" smd rect
			(at 0 1.500124)
			(size 0.6858 0.3048)
			(layers "F.Cu" "F.Mask" "F.Paste")
			(net "VR_P1V15_BMC_STBY_FB")
		)
		(pad "5" smd rect
			(at 0 1.999996)
			(size 0.6858 0.3048)
			(layers "F.Cu" "F.Mask" "F.Paste")
			(net "PWRGD_P1V15_BMC_STBY_R")
		)
		(pad "6" smd rect
			(at 2.871216 1.999996)
			(size 0.6858 0.3048)
			(layers "F.Cu" "F.Mask" "F.Paste")
			(net "PWRGD_P1V2_BMC_STBY")
		)
		(pad "7" smd rect
			(at 2.871216 1.500124)
			(size 0.6858 0.3048)
			(layers "F.Cu" "F.Mask" "F.Paste")
			(net "P3V3_STBY")
		)
		(pad "8" smd rect
			(at 2.871216 0.999998)
			(size 0.6858 0.3048)
			(layers "F.Cu" "F.Mask" "F.Paste")
			(net "P3V3_STBY")
		)
		(pad "9" smd rect
			(at 2.871216 0.500126)
			(size 0.6858 0.3048)
			(layers "F.Cu" "F.Mask" "F.Paste")
			(net "P3V3_STBY")
		)
		(pad "10" smd rect
			(at 2.871216 0)
			(size 0.6858 0.3048)
			(layers "F.Cu" "F.Mask" "F.Paste")
			(net "P3V3_STBY")
		)
		(pad "11" smd rect
			(at 1.435608 0.999998)
			(size 1.6764 2.5908)
			(layers "F.Cu" "F.Mask" "F.Paste")
			(net "GND")
		)
	)
)
